(kicad_pcb
	(version 20260206)
	(generator "pcbnew")
	(generator_version "10.0")
	(general
		(thickness 1.6)
		(legacy_teardrops no)
	)
	(paper "A4")
	(title_block
		(title "01162023_DA0F0TEBIF0_F0T_Expander_BD_F_brd_V02_OCP.brd")
		(comment 1 "Grand Teton / footprints 8478-8485 of 9728")
	)
	(layers
		(0 "F.Cu" signal "TOP")
		(4 "In1.Cu" signal "GND")
		(6 "In2.Cu" signal "VCC")
		(8 "In3.Cu" signal "VCC1")
		(10 "In4.Cu" signal "GND1")
		(12 "In5.Cu" signal "IN1")
		(14 "In6.Cu" signal "GND2")
		(16 "In7.Cu" signal "IN2")
		(18 "In8.Cu" signal "GND3")
		(20 "In9.Cu" signal "IN3")
		(22 "In10.Cu" signal "GND4")
		(24 "In11.Cu" signal "IN4")
		(26 "In12.Cu" signal "GND5")
		(28 "In13.Cu" signal "IN5")
		(30 "In14.Cu" signal "GND6")
		(32 "In15.Cu" signal "IN6")
		(34 "In16.Cu" signal "GND7")
		(2 "B.Cu" signal "BOTTOM")
		(9 "F.Adhes" user "F.Adhesive")
		(11 "B.Adhes" user "B.Adhesive")
		(13 "F.Paste" user "Package Geometry/Pastemask Top")
		(15 "B.Paste" user "Package Geometry/Pastemask Bottom")
		(5 "F.SilkS" user "Ref Des/Silkscreen Top")
		(7 "B.SilkS" user "Ref Des/Silkscreen Bottom")
		(1 "F.Mask" user "Board Geometry/Soldermask Top")
		(3 "B.Mask" user "Board Geometry/Soldermask Bottom")
		(17 "Dwgs.User" user "User.Drawings")
		(19 "Cmts.User" user "User.Comments")
		(21 "Eco1.User" user "User.Eco1")
		(23 "Eco2.User" user "User.Eco2")
		(25 "Edge.Cuts" user "Board Geometry/Outline")
		(27 "Margin" user)
		(31 "F.CrtYd" user "Package Geometry/Place Bound Top")
		(29 "B.CrtYd" user "Package Geometry/Place Bound Bottom")
		(35 "F.Fab" user "Ref Des/Assembly Top")
		(33 "B.Fab" user "Ref Des/Assembly Bottom")
	)
	(footprint ""
		(layer "B.Cu")
		(at 224.81794 -196.987922 90)
		(property "Reference" "R462"
			(at 0 0 90)
			(layer "B.SilkS")
			(hide yes)
			(effects
				(font
					(size 1.27 1.27)
				)
				(justify mirror)
			)
		)
		(property "Value" ""
			(at 0 0 90)
			(layer "B.Fab")
			(effects
				(font
					(size 1.27 1.27)
				)
				(justify mirror)
			)
		)
		(duplicate_pad_numbers_are_jumpers no)
		(fp_line
			(start 0.7874 -0.4064)
			(end -0.7874 -0.4064)
			(stroke
				(width 0.1524)
				(type default)
			)
			(layer "B.SilkS")
		)
		(fp_line
			(start -0.7874 -0.4064)
			(end -0.7874 0.4064)
			(stroke
				(width 0.1524)
				(type default)
			)
			(layer "B.SilkS")
		)
		(fp_line
			(start 0.7874 0.4064)
			(end 0.7874 -0.4064)
			(stroke
				(width 0.1524)
				(type default)
			)
			(layer "B.SilkS")
		)
		(fp_line
			(start -0.7874 0.4064)
			(end 0.7874 0.4064)
			(stroke
				(width 0.1524)
				(type default)
			)
			(layer "B.SilkS")
		)
		(fp_line
			(start 0.67945 -0.305054)
			(end 0.12065 -0.305054)
			(stroke
				(width 0.1)
				(type default)
			)
			(layer "B.Fab")
		)
		(fp_line
			(start 0.12065 -0.305054)
			(end 0.12065 -0.2794)
			(stroke
				(width 0.1)
				(type default)
			)
			(layer "B.Fab")
		)
		(fp_line
			(start -0.12065 -0.3048)
			(end -0.67945 -0.3048)
			(stroke
				(width 0.1)
				(type default)
			)
			(layer "B.Fab")
		)
		(fp_line
			(start -0.67945 -0.3048)
			(end -0.67945 0.3048)
			(stroke
				(width 0.1)
				(type default)
			)
			(layer "B.Fab")
		)
		(fp_line
			(start 0.12065 -0.2794)
			(end -0.12065 -0.2794)
			(stroke
				(width 0.1)
				(type default)
			)
			(layer "B.Fab")
		)
		(fp_line
			(start -0.12065 -0.2794)
			(end -0.12065 -0.3048)
			(stroke
				(width 0.1)
				(type default)
			)
			(layer "B.Fab")
		)
		(fp_line
			(start 0.12065 0.2794)
			(end 0.12065 0.3048)
			(stroke
				(width 0.1)
				(type default)
			)
			(layer "B.Fab")
		)
		(fp_line
			(start -0.120396 0.2794)
			(end 0.12065 0.2794)
			(stroke
				(width 0.1)
				(type default)
			)
			(layer "B.Fab")
		)
		(fp_line
			(start 0.67945 0.3048)
			(end 0.67945 -0.305054)
			(stroke
				(width 0.1)
				(type default)
			)
			(layer "B.Fab")
		)
		(fp_line
			(start 0.12065 0.3048)
			(end 0.67945 0.3048)
			(stroke
				(width 0.1)
				(type default)
			)
			(layer "B.Fab")
		)
		(fp_line
			(start -0.120396 0.3048)
			(end -0.120396 0.2794)
			(stroke
				(width 0.1)
				(type default)
			)
			(layer "B.Fab")
		)
		(fp_line
			(start -0.67945 0.3048)
			(end -0.120396 0.3048)
			(stroke
				(width 0.1)
				(type default)
			)
			(layer "B.Fab")
		)
		(pad "1" smd circle
			(at 0.40005 0 270)
			(size 0 0)
			(layers "B.Cu" "B.Mask" "B.Paste")
			(net "SPI_BIC1_CLK_R")
		)
		(pad "2" smd circle
			(at -0.40005 0 270)
			(size 0 0)
			(layers "B.Cu" "B.Mask" "B.Paste")
			(net "SPI_BIC1_CLK_R1")
		)
	)
	(footprint ""
		(layer "B.Cu")
		(at 109.615732 -354.313236 180)
		(property "Reference" "C4179"
			(at 0 0 0)
			(layer "B.SilkS")
			(hide yes)
			(effects
				(font
					(size 1.27 1.27)
				)
				(justify mirror)
			)
		)
		(property "Value" ""
			(at 0 0 0)
			(layer "B.Fab")
			(effects
				(font
					(size 1.27 1.27)
				)
				(justify mirror)
			)
		)
		(duplicate_pad_numbers_are_jumpers no)
		(fp_line
			(start 0.7874 0.4064)
			(end 0.7874 -0.4064)
			(stroke
				(width 0.1524)
				(type default)
			)
			(layer "B.SilkS")
		)
		(fp_line
			(start 0.7874 -0.4064)
			(end -0.7874 -0.4064)
			(stroke
				(width 0.1524)
				(type default)
			)
			(layer "B.SilkS")
		)
		(fp_line
			(start -0.7874 0.4064)
			(end 0.7874 0.4064)
			(stroke
				(width 0.1524)
				(type default)
			)
			(layer "B.SilkS")
		)
		(fp_line
			(start -0.7874 -0.4064)
			(end -0.7874 0.4064)
			(stroke
				(width 0.1524)
				(type default)
			)
			(layer "B.SilkS")
		)
		(fp_line
			(start 0.67945 0.3048)
			(end 0.67945 -0.305054)
			(stroke
				(width 0.1)
				(type default)
			)
			(layer "B.Fab")
		)
		(fp_line
			(start 0.67945 -0.305054)
			(end 0.12065 -0.305054)
			(stroke
				(width 0.1)
				(type default)
			)
			(layer "B.Fab")
		)
		(fp_line
			(start 0.12065 0.3048)
			(end 0.67945 0.3048)
			(stroke
				(width 0.1)
				(type default)
			)
			(layer "B.Fab")
		)
		(fp_line
			(start 0.12065 0.2794)
			(end 0.12065 0.3048)
			(stroke
				(width 0.1)
				(type default)
			)
			(layer "B.Fab")
		)
		(fp_line
			(start 0.12065 -0.2794)
			(end -0.12065 -0.2794)
			(stroke
				(width 0.1)
				(type default)
			)
			(layer "B.Fab")
		)
		(fp_line
			(start 0.12065 -0.305054)
			(end 0.12065 -0.2794)
			(stroke
				(width 0.1)
				(type default)
			)
			(layer "B.Fab")
		)
		(fp_line
			(start -0.120396 0.3048)
			(end -0.120396 0.2794)
			(stroke
				(width 0.1)
				(type default)
			)
			(layer "B.Fab")
		)
		(fp_line
			(start -0.120396 0.2794)
			(end 0.12065 0.2794)
			(stroke
				(width 0.1)
				(type default)
			)
			(layer "B.Fab")
		)
		(fp_line
			(start -0.12065 -0.2794)
			(end -0.12065 -0.3048)
			(stroke
				(width 0.1)
				(type default)
			)
			(layer "B.Fab")
		)
		(fp_line
			(start -0.12065 -0.3048)
			(end -0.67945 -0.3048)
			(stroke
				(width 0.1)
				(type default)
			)
			(layer "B.Fab")
		)
		(fp_line
			(start -0.67945 0.3048)
			(end -0.120396 0.3048)
			(stroke
				(width 0.1)
				(type default)
			)
			(layer "B.Fab")
		)
		(fp_line
			(start -0.67945 -0.3048)
			(end -0.67945 0.3048)
			(stroke
				(width 0.1)
				(type default)
			)
			(layer "B.Fab")
		)
		(pad "1" smd circle
			(at 0.40005 0)
			(size 0 0)
			(layers "B.Cu" "B.Mask" "B.Paste")
			(net "P3V3_CLK_BUFFER_9ZXL0451E_S3_VZX3P3")
		)
		(pad "2" smd circle
			(at -0.40005 0)
			(size 0 0)
			(layers "B.Cu" "B.Mask" "B.Paste")
			(net "GND")
		)
	)
	(footprint ""
		(layer "B.Cu")
		(at 253.918212 -83.669378 -90)
		(property "Reference" "C2640"
			(at 0 0 90)
			(layer "B.SilkS")
			(hide yes)
			(effects
				(font
					(size 1.27 1.27)
				)
				(justify mirror)
			)
		)
		(property "Value" ""
			(at 0 0 90)
			(layer "B.Fab")
			(effects
				(font
					(size 1.27 1.27)
				)
				(justify mirror)
			)
		)
		(duplicate_pad_numbers_are_jumpers no)
		(fp_line
			(start -0.7874 0.4064)
			(end 0.7874 0.4064)
			(stroke
				(width 0.1524)
				(type default)
			)
			(layer "B.SilkS")
		)
		(fp_line
			(start 0.7874 0.4064)
			(end 0.7874 -0.4064)
			(stroke
				(width 0.1524)
				(type default)
			)
			(layer "B.SilkS")
		)
		(fp_line
			(start -0.7874 -0.4064)
			(end -0.7874 0.4064)
			(stroke
				(width 0.1524)
				(type default)
			)
			(layer "B.SilkS")
		)
		(fp_line
			(start 0.7874 -0.4064)
			(end -0.7874 -0.4064)
			(stroke
				(width 0.1524)
				(type default)
			)
			(layer "B.SilkS")
		)
		(fp_line
			(start -0.67945 0.3048)
			(end -0.120396 0.3048)
			(stroke
				(width 0.1)
				(type default)
			)
			(layer "B.Fab")
		)
		(fp_line
			(start -0.120396 0.3048)
			(end -0.120396 0.2794)
			(stroke
				(width 0.1)
				(type default)
			)
			(layer "B.Fab")
		)
		(fp_line
			(start 0.12065 0.3048)
			(end 0.67945 0.3048)
			(stroke
				(width 0.1)
				(type default)
			)
			(layer "B.Fab")
		)
		(fp_line
			(start 0.67945 0.3048)
			(end 0.67945 -0.305054)
			(stroke
				(width 0.1)
				(type default)
			)
			(layer "B.Fab")
		)
		(fp_line
			(start -0.120396 0.2794)
			(end 0.12065 0.2794)
			(stroke
				(width 0.1)
				(type default)
			)
			(layer "B.Fab")
		)
		(fp_line
			(start 0.12065 0.2794)
			(end 0.12065 0.3048)
			(stroke
				(width 0.1)
				(type default)
			)
			(layer "B.Fab")
		)
		(fp_line
			(start -0.12065 -0.2794)
			(end -0.12065 -0.3048)
			(stroke
				(width 0.1)
				(type default)
			)
			(layer "B.Fab")
		)
		(fp_line
			(start 0.12065 -0.2794)
			(end -0.12065 -0.2794)
			(stroke
				(width 0.1)
				(type default)
			)
			(layer "B.Fab")
		)
		(fp_line
			(start -0.67945 -0.3048)
			(end -0.67945 0.3048)
			(stroke
				(width 0.1)
				(type default)
			)
			(layer "B.Fab")
		)
		(fp_line
			(start -0.12065 -0.3048)
			(end -0.67945 -0.3048)
			(stroke
				(width 0.1)
				(type default)
			)
			(layer "B.Fab")
		)
		(fp_line
			(start 0.12065 -0.305054)
			(end 0.12065 -0.2794)
			(stroke
				(width 0.1)
				(type default)
			)
			(layer "B.Fab")
		)
		(fp_line
			(start 0.67945 -0.305054)
			(end 0.12065 -0.305054)
			(stroke
				(width 0.1)
				(type default)
			)
			(layer "B.Fab")
		)
		(pad "1" smd circle
			(at 0.40005 0 90)
			(size 0 0)
			(layers "B.Cu" "B.Mask" "B.Paste")
			(net "P3V3_CLK_GEN_VDDXTAL_CK440")
		)
		(pad "2" smd circle
			(at -0.40005 0 90)
			(size 0 0)
			(layers "B.Cu" "B.Mask" "B.Paste")
			(net "GND")
		)
	)
	(footprint ""
		(layer "B.Cu")
		(at 397.70812 -303.024794 180)
		(property "Reference" "C3536"
			(at 0 0 0)
			(layer "B.SilkS")
			(hide yes)
			(effects
				(font
					(size 1.27 1.27)
				)
				(justify mirror)
			)
		)
		(property "Value" ""
			(at 0 0 0)
			(layer "B.Fab")
			(effects
				(font
					(size 1.27 1.27)
				)
				(justify mirror)
			)
		)
		(duplicate_pad_numbers_are_jumpers no)
		(fp_line
			(start 0.299974 0.150114)
			(end 0.299974 -0.150114)
			(stroke
				(width 0.1)
				(type default)
			)
			(layer "B.Fab")
		)
		(fp_line
			(start 0.299974 -0.150114)
			(end -0.299974 -0.150114)
			(stroke
				(width 0.1)
				(type default)
			)
			(layer "B.Fab")
		)
		(fp_line
			(start -0.299974 0.150114)
			(end 0.299974 0.150114)
			(stroke
				(width 0.1)
				(type default)
			)
			(layer "B.Fab")
		)
		(fp_line
			(start -0.299974 -0.150114)
			(end -0.299974 0.150114)
			(stroke
				(width 0.1)
				(type default)
			)
			(layer "B.Fab")
		)
		(pad "1" smd rect
			(at 0.2667 0)
			(size 0.3048 0.381)
			(layers "B.Cu" "B.Mask" "B.Paste")
			(net "P1V8_VDDA_PEX3")
		)
		(pad "2" smd rect
			(at -0.2667 0)
			(size 0.3048 0.381)
			(layers "B.Cu" "B.Mask" "B.Paste")
			(net "GND")
		)
	)
	(footprint ""
		(layer "B.Cu")
		(at 233.292142 -79.305912 180)
		(property "Reference" "C2612"
			(at 0 0 0)
			(layer "B.SilkS")
			(hide yes)
			(effects
				(font
					(size 1.27 1.27)
				)
				(justify mirror)
			)
		)
		(property "Value" ""
			(at 0 0 0)
			(layer "B.Fab")
			(effects
				(font
					(size 1.27 1.27)
				)
				(justify mirror)
			)
		)
		(duplicate_pad_numbers_are_jumpers no)
		(fp_line
			(start 0.7874 0.4064)
			(end 0.7874 -0.4064)
			(stroke
				(width 0.1524)
				(type default)
			)
			(layer "B.SilkS")
		)
		(fp_line
			(start 0.7874 -0.4064)
			(end -0.7874 -0.4064)
			(stroke
				(width 0.1524)
				(type default)
			)
			(layer "B.SilkS")
		)
		(fp_line
			(start -0.7874 0.4064)
			(end 0.7874 0.4064)
			(stroke
				(width 0.1524)
				(type default)
			)
			(layer "B.SilkS")
		)
		(fp_line
			(start -0.7874 -0.4064)
			(end -0.7874 0.4064)
			(stroke
				(width 0.1524)
				(type default)
			)
			(layer "B.SilkS")
		)
		(fp_line
			(start 0.67945 0.3048)
			(end 0.67945 -0.305054)
			(stroke
				(width 0.1)
				(type default)
			)
			(layer "B.Fab")
		)
		(fp_line
			(start 0.67945 -0.305054)
			(end 0.12065 -0.305054)
			(stroke
				(width 0.1)
				(type default)
			)
			(layer "B.Fab")
		)
		(fp_line
			(start 0.12065 0.3048)
			(end 0.67945 0.3048)
			(stroke
				(width 0.1)
				(type default)
			)
			(layer "B.Fab")
		)
		(fp_line
			(start 0.12065 0.2794)
			(end 0.12065 0.3048)
			(stroke
				(width 0.1)
				(type default)
			)
			(layer "B.Fab")
		)
		(fp_line
			(start 0.12065 -0.2794)
			(end -0.12065 -0.2794)
			(stroke
				(width 0.1)
				(type default)
			)
			(layer "B.Fab")
		)
		(fp_line
			(start 0.12065 -0.305054)
			(end 0.12065 -0.2794)
			(stroke
				(width 0.1)
				(type default)
			)
			(layer "B.Fab")
		)
		(fp_line
			(start -0.120396 0.3048)
			(end -0.120396 0.2794)
			(stroke
				(width 0.1)
				(type default)
			)
			(layer "B.Fab")
		)
		(fp_line
			(start -0.120396 0.2794)
			(end 0.12065 0.2794)
			(stroke
				(width 0.1)
				(type default)
			)
			(layer "B.Fab")
		)
		(fp_line
			(start -0.12065 -0.2794)
			(end -0.12065 -0.3048)
			(stroke
				(width 0.1)
				(type default)
			)
			(layer "B.Fab")
		)
		(fp_line
			(start -0.12065 -0.3048)
			(end -0.67945 -0.3048)
			(stroke
				(width 0.1)
				(type default)
			)
			(layer "B.Fab")
		)
		(fp_line
			(start -0.67945 0.3048)
			(end -0.120396 0.3048)
			(stroke
				(width 0.1)
				(type default)
			)
			(layer "B.Fab")
		)
		(fp_line
			(start -0.67945 -0.3048)
			(end -0.67945 0.3048)
			(stroke
				(width 0.1)
				(type default)
			)
			(layer "B.Fab")
		)
		(pad "1" smd circle
			(at 0.40005 0)
			(size 0 0)
			(layers "B.Cu" "B.Mask" "B.Paste")
			(net "P3V3_AUX")
		)
		(pad "2" smd circle
			(at -0.40005 0)
			(size 0 0)
			(layers "B.Cu" "B.Mask" "B.Paste")
			(net "GND")
		)
	)
	(footprint ""
		(layer "B.Cu")
		(at 392.749786 -300.174914)
		(property "Reference" "C3534"
			(at 0 0 0)
			(layer "B.SilkS")
			(hide yes)
			(effects
				(font
					(size 1.27 1.27)
				)
				(justify mirror)
			)
		)
		(property "Value" ""
			(at 0 0 0)
			(layer "B.Fab")
			(effects
				(font
					(size 1.27 1.27)
				)
				(justify mirror)
			)
		)
		(duplicate_pad_numbers_are_jumpers no)
		(fp_line
			(start -0.299974 -0.150114)
			(end -0.299974 0.150114)
			(stroke
				(width 0.1)
				(type default)
			)
			(layer "B.Fab")
		)
		(fp_line
			(start -0.299974 0.150114)
			(end 0.299974 0.150114)
			(stroke
				(width 0.1)
				(type default)
			)
			(layer "B.Fab")
		)
		(fp_line
			(start 0.299974 -0.150114)
			(end -0.299974 -0.150114)
			(stroke
				(width 0.1)
				(type default)
			)
			(layer "B.Fab")
		)
		(fp_line
			(start 0.299974 0.150114)
			(end 0.299974 -0.150114)
			(stroke
				(width 0.1)
				(type default)
			)
			(layer "B.Fab")
		)
		(pad "1" smd rect
			(at 0.2667 0 180)
			(size 0.3048 0.381)
			(layers "B.Cu" "B.Mask" "B.Paste")
			(net "P1V8_VDDA_PEX3")
		)
		(pad "2" smd rect
			(at -0.2667 0 180)
			(size 0.3048 0.381)
			(layers "B.Cu" "B.Mask" "B.Paste")
			(net "GND")
		)
	)
	(footprint ""
		(layer "B.Cu")
		(at 296.599864 -292.099746 90)
		(property "Reference" "C1734"
			(at 0 0 90)
			(layer "B.SilkS")
			(hide yes)
			(effects
				(font
					(size 1.27 1.27)
				)
				(justify mirror)
			)
		)
		(property "Value" ""
			(at 0 0 90)
			(layer "B.Fab")
			(effects
				(font
					(size 1.27 1.27)
				)
				(justify mirror)
			)
		)
		(duplicate_pad_numbers_are_jumpers no)
		(fp_line
			(start 0.299974 -0.150114)
			(end -0.299974 -0.150114)
			(stroke
				(width 0.1)
				(type default)
			)
			(layer "B.Fab")
		)
		(fp_line
			(start -0.299974 -0.150114)
			(end -0.299974 0.150114)
			(stroke
				(width 0.1)
				(type default)
			)
			(layer "B.Fab")
		)
		(fp_line
			(start 0.299974 0.150114)
			(end 0.299974 -0.150114)
			(stroke
				(width 0.1)
				(type default)
			)
			(layer "B.Fab")
		)
		(fp_line
			(start -0.299974 0.150114)
			(end 0.299974 0.150114)
			(stroke
				(width 0.1)
				(type default)
			)
			(layer "B.Fab")
		)
		(pad "1" smd rect
			(at 0.2667 0 270)
			(size 0.3048 0.381)
			(layers "B.Cu" "B.Mask" "B.Paste")
			(net "P0V8_SERDES_VDDA_PEX2")
		)
		(pad "2" smd rect
			(at -0.2667 0 270)
			(size 0.3048 0.381)
			(layers "B.Cu" "B.Mask" "B.Paste")
			(net "GND")
		)
	)
	(footprint ""
		(layer "B.Cu")
		(at 213.106 -206.121 90)
		(property "Reference" "R6307"
			(at 0 0 90)
			(layer "B.SilkS")
			(hide yes)
			(effects
				(font
					(size 1.27 1.27)
				)
				(justify mirror)
			)
		)
		(property "Value" ""
			(at 0 0 90)
			(layer "B.Fab")
			(effects
				(font
					(size 1.27 1.27)
				)
				(justify mirror)
			)
		)
		(duplicate_pad_numbers_are_jumpers no)
		(fp_line
			(start 0.7874 -0.4064)
			(end -0.7874 -0.4064)
			(stroke
				(width 0.1524)
				(type default)
			)
			(layer "B.SilkS")
		)
		(fp_line
			(start -0.7874 -0.4064)
			(end -0.7874 0.4064)
			(stroke
				(width 0.1524)
				(type default)
			)
			(layer "B.SilkS")
		)
		(fp_line
			(start 0.7874 0.4064)
			(end 0.7874 -0.4064)
			(stroke
				(width 0.1524)
				(type default)
			)
			(layer "B.SilkS")
		)
		(fp_line
			(start -0.7874 0.4064)
			(end 0.7874 0.4064)
			(stroke
				(width 0.1524)
				(type default)
			)
			(layer "B.SilkS")
		)
		(fp_line
			(start 0.67945 -0.305054)
			(end 0.12065 -0.305054)
			(stroke
				(width 0.1)
				(type default)
			)
			(layer "B.Fab")
		)
		(fp_line
			(start 0.12065 -0.305054)
			(end 0.12065 -0.2794)
			(stroke
				(width 0.1)
				(type default)
			)
			(layer "B.Fab")
		)
		(fp_line
			(start -0.12065 -0.3048)
			(end -0.67945 -0.3048)
			(stroke
				(width 0.1)
				(type default)
			)
			(layer "B.Fab")
		)
		(fp_line
			(start -0.67945 -0.3048)
			(end -0.67945 0.3048)
			(stroke
				(width 0.1)
				(type default)
			)
			(layer "B.Fab")
		)
		(fp_line
			(start 0.12065 -0.2794)
			(end -0.12065 -0.2794)
			(stroke
				(width 0.1)
				(type default)
			)
			(layer "B.Fab")
		)
		(fp_line
			(start -0.12065 -0.2794)
			(end -0.12065 -0.3048)
			(stroke
				(width 0.1)
				(type default)
			)
			(layer "B.Fab")
		)
		(fp_line
			(start 0.12065 0.2794)
			(end 0.12065 0.3048)
			(stroke
				(width 0.1)
				(type default)
			)
			(layer "B.Fab")
		)
		(fp_line
			(start -0.120396 0.2794)
			(end 0.12065 0.2794)
			(stroke
				(width 0.1)
				(type default)
			)
			(layer "B.Fab")
		)
		(fp_line
			(start 0.67945 0.3048)
			(end 0.67945 -0.305054)
			(stroke
				(width 0.1)
				(type default)
			)
			(layer "B.Fab")
		)
		(fp_line
			(start 0.12065 0.3048)
			(end 0.67945 0.3048)
			(stroke
				(width 0.1)
				(type default)
			)
			(layer "B.Fab")
		)
		(fp_line
			(start -0.120396 0.3048)
			(end -0.120396 0.2794)
			(stroke
				(width 0.1)
				(type default)
			)
			(layer "B.Fab")
		)
		(fp_line
			(start -0.67945 0.3048)
			(end -0.120396 0.3048)
			(stroke
				(width 0.1)
				(type default)
			)
			(layer "B.Fab")
		)
		(pad "1" smd circle
			(at 0.40005 0 270)
			(size 0 0)
			(layers "B.Cu" "B.Mask" "B.Paste")
			(net "SMB_NIC4_LS_SCL")
		)
		(pad "2" smd circle
			(at -0.40005 0 270)
			(size 0 0)
			(layers "B.Cu" "B.Mask" "B.Paste")
			(net "SMB_NIC4_LS_R_SCL")
		)
	)
)
